(kicad_pcb
	(version 20260206)
	(generator "pcbnew")
	(generator_version "10.0")
	(general
		(thickness 1.6)
		(legacy_teardrops no)
	)
	(paper "A4")
	(title_block
		(title "Wiwynn_Tioga_Pass_MB.brd")
		(comment 1 "Tioga Pass / footprints 681-687 of 4770")
	)
	(layers
		(0 "F.Cu" signal "TOP")
		(4 "In1.Cu" signal "L2GND")
		(6 "In2.Cu" signal "L3")
		(8 "In3.Cu" signal "L4GND")
		(10 "In4.Cu" signal "L5")
		(12 "In5.Cu" signal "L6GND")
		(14 "In6.Cu" signal "L7VCC")
		(16 "In7.Cu" signal "L8VCC")
		(18 "In8.Cu" signal "L9GND")
		(20 "In9.Cu" signal "L10")
		(22 "In10.Cu" signal "L11GND")
		(24 "In11.Cu" signal "L12")
		(26 "In12.Cu" signal "L13GND")
		(2 "B.Cu" signal "BOTTOM")
		(9 "F.Adhes" user "F.Adhesive")
		(11 "B.Adhes" user "B.Adhesive")
		(13 "F.Paste" user "Package Geometry/Pastemask Top")
		(15 "B.Paste" user "Package Geometry/Pastemask Bottom")
		(5 "F.SilkS" user "Ref Des/Silkscreen Top")
		(7 "B.SilkS" user "Ref Des/Silkscreen Bottom")
		(1 "F.Mask" user "Board Geometry/Soldermask Top")
		(3 "B.Mask" user "Board Geometry/Soldermask Bottom")
		(17 "Dwgs.User" user "User.Drawings")
		(19 "Cmts.User" user "User.Comments")
		(21 "Eco1.User" user "User.Eco1")
		(23 "Eco2.User" user "User.Eco2")
		(25 "Edge.Cuts" user "Board Geometry/Outline")
		(27 "Margin" user)
		(31 "F.CrtYd" user "Package Geometry/Place Bound Top")
		(29 "B.CrtYd" user "Package Geometry/Place Bound Bottom")
		(35 "F.Fab" user "Ref Des/Assembly Top")
		(33 "B.Fab" user "Ref Des/Assembly Bottom")
	)
	(footprint ""
		(layer "F.Cu")
		(at 405.257 -23.0505)
		(property "Reference" "R25W89"
			(at -0.8382 -0.67818 0)
			(unlocked yes)
			(layer "F.SilkS")
			(effects
				(font
					(size 0.4064 0.254)
					(thickness 0.1524)
				)
				(justify left)
			)
		)
		(property "Value" ""
			(at 0 0 0)
			(layer "F.Fab")
			(effects
				(font
					(size 1.27 1.27)
				)
			)
		)
		(duplicate_pad_numbers_are_jumpers no)
		(fp_poly
			(pts
				(xy -0.2794 -0.1016) (xy 0.2794 -0.1016) (xy 0.2794 0.9906) (xy -0.2794 0.9906)
			)
			(stroke
				(width 0)
				(type default)
			)
			(fill no)
			(layer "F.CrtYd")
		)
		(fp_line
			(start -0.2794 -0.1016)
			(end -0.2794 0.9906)
			(stroke
				(width 0.1)
				(type default)
			)
			(layer "F.Fab")
		)
		(fp_line
			(start -0.2794 0.9906)
			(end 0.2794 0.9906)
			(stroke
				(width 0.1)
				(type default)
			)
			(layer "F.Fab")
		)
		(fp_line
			(start 0.2794 -0.1016)
			(end -0.2794 -0.1016)
			(stroke
				(width 0.1)
				(type default)
			)
			(layer "F.Fab")
		)
		(fp_line
			(start 0.2794 0.9906)
			(end 0.2794 -0.1016)
			(stroke
				(width 0.1)
				(type default)
			)
			(layer "F.Fab")
		)
		(pad "1" smd rect
			(at 0 0)
			(size 0.508 0.508)
			(layers "F.Cu" "F.Mask" "F.Paste")
			(net "RMII_BMC_PCH_SPRNGVLLE_TXD0_R")
		)
		(pad "2" smd rect
			(at 0 0.889)
			(size 0.508 0.508)
			(layers "F.Cu" "F.Mask" "F.Paste")
			(net "RMII_BMC_PCH_SPRNGVLLE_TXD0")
		)
		(zone
			(layer "F.Cu")
			(hatch none 0.5)
			(connect_pads
				(clearance 0)
			)
			(min_thickness 0.25)
			(keepout
				(tracks allowed)
				(vias not_allowed)
				(pads allowed)
				(copperpour not_allowed)
				(footprints allowed)
			)
			(placement
				(enabled no)
				(sheetname "")
			)
			(fill
				(thermal_gap 0.5)
				(thermal_bridge_width 0.5)
				(island_removal_mode 0)
			)
			(polygon
				(pts
					(xy 405.003 -22.7965) (xy 405.511 -22.7965) (xy 405.511 -22.4155) (xy 405.003 -22.4155)
				)
			)
		)
		(zone
			(layer "F.Cu")
			(hatch none 0.5)
			(connect_pads
				(clearance 0)
			)
			(min_thickness 0.25)
			(keepout
				(tracks not_allowed)
				(vias allowed)
				(pads allowed)
				(copperpour not_allowed)
				(footprints allowed)
			)
			(placement
				(enabled no)
				(sheetname "")
			)
			(fill
				(thermal_gap 0.5)
				(thermal_bridge_width 0.5)
				(island_removal_mode 0)
			)
			(polygon
				(pts
					(xy 405.003 -22.4155) (xy 405.511 -22.4155) (xy 405.511 -22.7965) (xy 405.003 -22.7965)
				)
			)
		)
	)
	(footprint ""
		(layer "F.Cu")
		(at 406.9461 -64.135 90)
		(property "Reference" "R8E4"
			(at 0 0 90)
			(layer "F.SilkS")
			(hide yes)
			(effects
				(font
					(size 1.27 1.27)
				)
			)
		)
		(property "Value" ""
			(at 0 0 90)
			(layer "F.Fab")
			(effects
				(font
					(size 1.27 1.27)
				)
			)
		)
		(duplicate_pad_numbers_are_jumpers no)
		(fp_poly
			(pts
				(xy -0.2794 -0.1016) (xy 0.2794 -0.1016) (xy 0.2794 0.9906) (xy -0.2794 0.9906)
			)
			(stroke
				(width 0)
				(type default)
			)
			(fill no)
			(layer "F.CrtYd")
		)
		(pad "1" smd rect
			(at 0 0 90)
			(size 0.508 0.508)
			(layers "F.Cu" "F.Mask" "F.Paste")
			(net "SPI_PCH_MOSI")
		)
		(pad "2" smd rect
			(at 0 0.889 90)
			(size 0.508 0.508)
			(layers "F.Cu" "F.Mask" "F.Paste")
			(net "GND")
		)
		(zone
			(layer "F.Cu")
			(hatch none 0.5)
			(connect_pads
				(clearance 0)
			)
			(min_thickness 0.25)
			(keepout
				(tracks allowed)
				(vias not_allowed)
				(pads allowed)
				(copperpour not_allowed)
				(footprints allowed)
			)
			(placement
				(enabled no)
				(sheetname "")
			)
			(fill
				(thermal_gap 0.5)
				(thermal_bridge_width 0.5)
				(island_removal_mode 0)
			)
			(polygon
				(pts
					(xy 407.2001 -63.881) (xy 407.2001 -64.389) (xy 407.5811 -64.389) (xy 407.5811 -63.881)
				)
			)
		)
		(zone
			(layer "F.Cu")
			(hatch none 0.5)
			(connect_pads
				(clearance 0)
			)
			(min_thickness 0.25)
			(keepout
				(tracks not_allowed)
				(vias allowed)
				(pads allowed)
				(copperpour not_allowed)
				(footprints allowed)
			)
			(placement
				(enabled no)
				(sheetname "")
			)
			(fill
				(thermal_gap 0.5)
				(thermal_bridge_width 0.5)
				(island_removal_mode 0)
			)
			(polygon
				(pts
					(xy 407.5811 -63.881) (xy 407.5811 -64.389) (xy 407.2001 -64.389) (xy 407.2001 -63.881)
				)
			)
		)
	)
	(footprint ""
		(layer "F.Cu")
		(at 442.89472 -129.58318)
		(property "Reference" "F8B1"
			(at 0 0 0)
			(layer "F.SilkS")
			(hide yes)
			(effects
				(font
					(size 1.27 1.27)
				)
			)
		)
		(property "Value" "*"
			(at -0.02032 -4.5212 0)
			(unlocked yes)
			(layer "F.Fab")
			(hide yes)
			(effects
				(font
					(size 1.27 1.016)
					(thickness 0.1524)
				)
			)
		)
		(property "Device Type" "FUSE-3A75V-GP_DISCRET-G5-FUSE-A"
			(at -0.02032 -6.0452 0)
			(unlocked yes)
			(layer "F.Fab")
			(hide yes)
			(effects
				(font
					(size 1.27 1.016)
					(thickness 0.1524)
				)
			)
		)
		(duplicate_pad_numbers_are_jumpers no)
		(fp_line
			(start -1.1684 -2.2225)
			(end -1.1684 2.2225)
			(stroke
				(width 0.1524)
				(type default)
			)
			(layer "F.SilkS")
		)
		(fp_line
			(start -1.1684 2.2225)
			(end 1.1684 2.2225)
			(stroke
				(width 0.1524)
				(type default)
			)
			(layer "F.SilkS")
		)
		(fp_line
			(start 1.1684 -2.2225)
			(end -1.1684 -2.2225)
			(stroke
				(width 0.1524)
				(type default)
			)
			(layer "F.SilkS")
		)
		(fp_line
			(start 1.1684 2.2225)
			(end 1.1684 -2.2225)
			(stroke
				(width 0.1524)
				(type default)
			)
			(layer "F.SilkS")
		)
		(fp_rect
			(start -0.7874 1.5875)
			(end 0.7874 -1.5875)
			(stroke
				(width 0)
				(type default)
			)
			(fill no)
			(layer "F.CrtYd")
		)
		(fp_poly
			(pts
				(xy -1.4224 2.2987) (xy -1.4224 -2.2987) (xy 1.4224 -2.2987) (xy 1.4224 -0.25146) (xy 0.7874 -0.25146)
				(xy 0.7874 -1.5875) (xy -0.7874 -1.5875) (xy -0.7874 1.5875) (xy 0.7874 1.5875) (xy 0.7874 -0.24892)
				(xy 1.4224 -0.24892) (xy 1.4224 2.2987)
			)
			(stroke
				(width 0)
				(type default)
			)
			(fill no)
			(layer "F.CrtYd")
		)
		(fp_rect
			(start -1.4224 2.2987)
			(end 1.4224 -2.2987)
			(stroke
				(width 0)
				(type default)
			)
			(fill no)
			(layer "F.Fab")
		)
		(pad "1" smd rect
			(at 0 -1.2446)
			(size 1.8288 1.4478)
			(layers "F.Cu" "F.Mask" "F.Paste")
			(net "P5V_HDD_SATA")
		)
		(pad "2" smd rect
			(at 0 1.2446)
			(size 1.8288 1.4478)
			(layers "F.Cu" "F.Mask" "F.Paste")
			(net "P5V")
		)
	)
	(footprint ""
		(layer "F.Cu")
		(at 14.732 -90.0684 -90)
		(property "Reference" "C1C23"
			(at 0 0 270)
			(layer "F.SilkS")
			(hide yes)
			(effects
				(font
					(size 1.27 1.27)
				)
			)
		)
		(property "Value" ""
			(at 0 0 270)
			(layer "F.Fab")
			(effects
				(font
					(size 1.27 1.27)
				)
			)
		)
		(duplicate_pad_numbers_are_jumpers no)
		(fp_rect
			(start 0.3048 0.9906)
			(end -0.3048 -0.1016)
			(stroke
				(width 0)
				(type default)
			)
			(fill no)
			(layer "F.CrtYd")
		)
		(fp_line
			(start -0.3048 0.9906)
			(end 0.3048 0.9906)
			(stroke
				(width 0.1)
				(type default)
			)
			(layer "F.Fab")
		)
		(fp_line
			(start 0.3048 0.9906)
			(end 0.3048 -0.1016)
			(stroke
				(width 0.1)
				(type default)
			)
			(layer "F.Fab")
		)
		(fp_line
			(start -0.3048 -0.1016)
			(end -0.3048 0.9906)
			(stroke
				(width 0.1)
				(type default)
			)
			(layer "F.Fab")
		)
		(fp_line
			(start 0.3048 -0.1016)
			(end -0.3048 -0.1016)
			(stroke
				(width 0.1)
				(type default)
			)
			(layer "F.Fab")
		)
		(pad "1" smd rect
			(at 0 0 270)
			(size 0.508 0.508)
			(layers "F.Cu" "F.Mask" "F.Paste")
			(net "VR_VRRDY_PVCCIN_CPU1")
		)
		(pad "2" smd rect
			(at 0 0.889 270)
			(size 0.508 0.508)
			(layers "F.Cu" "F.Mask" "F.Paste")
			(net "GND")
		)
		(zone
			(layer "F.Cu")
			(hatch none 0.5)
			(connect_pads
				(clearance 0)
			)
			(min_thickness 0.25)
			(keepout
				(tracks not_allowed)
				(vias allowed)
				(pads allowed)
				(copperpour not_allowed)
				(footprints allowed)
			)
			(placement
				(enabled no)
				(sheetname "")
			)
			(fill
				(thermal_gap 0.5)
				(thermal_bridge_width 0.5)
				(island_removal_mode 0)
			)
			(polygon
				(pts
					(xy 14.097 -89.8144) (xy 14.478 -89.8144) (xy 14.478 -90.3224) (xy 14.097 -90.3224)
				)
			)
		)
		(zone
			(layer "F.Cu")
			(hatch none 0.5)
			(connect_pads
				(clearance 0)
			)
			(min_thickness 0.25)
			(keepout
				(tracks allowed)
				(vias not_allowed)
				(pads allowed)
				(copperpour not_allowed)
				(footprints allowed)
			)
			(placement
				(enabled no)
				(sheetname "")
			)
			(fill
				(thermal_gap 0.5)
				(thermal_bridge_width 0.5)
				(island_removal_mode 0)
			)
			(polygon
				(pts
					(xy 14.097 -89.8144) (xy 14.478 -89.8144) (xy 14.478 -90.3224) (xy 14.097 -90.3224)
				)
			)
		)
	)
	(footprint ""
		(layer "F.Cu")
		(at 185.4454 -146.6723)
		(property "Reference" "R4A6"
			(at 0 0 0)
			(layer "F.SilkS")
			(hide yes)
			(effects
				(font
					(size 1.27 1.27)
				)
			)
		)
		(property "Value" ""
			(at 0 0 0)
			(layer "F.Fab")
			(effects
				(font
					(size 1.27 1.27)
				)
			)
		)
		(duplicate_pad_numbers_are_jumpers no)
		(fp_poly
			(pts
				(xy -0.2794 -0.1016) (xy 0.2794 -0.1016) (xy 0.2794 0.9906) (xy -0.2794 0.9906)
			)
			(stroke
				(width 0)
				(type default)
			)
			(fill no)
			(layer "F.CrtYd")
		)
		(fp_line
			(start -0.2794 -0.1016)
			(end -0.2794 0.9906)
			(stroke
				(width 0.1)
				(type default)
			)
			(layer "F.Fab")
		)
		(fp_line
			(start -0.2794 0.9906)
			(end 0.2794 0.9906)
			(stroke
				(width 0.1)
				(type default)
			)
			(layer "F.Fab")
		)
		(fp_line
			(start 0.2794 -0.1016)
			(end -0.2794 -0.1016)
			(stroke
				(width 0.1)
				(type default)
			)
			(layer "F.Fab")
		)
		(fp_line
			(start 0.2794 0.9906)
			(end 0.2794 -0.1016)
			(stroke
				(width 0.1)
				(type default)
			)
			(layer "F.Fab")
		)
		(pad "1" smd rect
			(at 0 0)
			(size 0.508 0.508)
			(layers "F.Cu" "F.Mask" "F.Paste")
			(net "PWRGD_PVTT_DEF_CPU0_R")
		)
		(pad "2" smd rect
			(at 0 0.889)
			(size 0.508 0.508)
			(layers "F.Cu" "F.Mask" "F.Paste")
			(net "PWRGD_PVTT_CPU0")
		)
		(zone
			(layer "F.Cu")
			(hatch none 0.5)
			(connect_pads
				(clearance 0)
			)
			(min_thickness 0.25)
			(keepout
				(tracks allowed)
				(vias not_allowed)
				(pads allowed)
				(copperpour not_allowed)
				(footprints allowed)
			)
			(placement
				(enabled no)
				(sheetname "")
			)
			(fill
				(thermal_gap 0.5)
				(thermal_bridge_width 0.5)
				(island_removal_mode 0)
			)
			(polygon
				(pts
					(xy 185.1914 -146.4183) (xy 185.6994 -146.4183) (xy 185.6994 -146.0373) (xy 185.1914 -146.0373)
				)
			)
		)
		(zone
			(layer "F.Cu")
			(hatch none 0.5)
			(connect_pads
				(clearance 0)
			)
			(min_thickness 0.25)
			(keepout
				(tracks not_allowed)
				(vias allowed)
				(pads allowed)
				(copperpour not_allowed)
				(footprints allowed)
			)
			(placement
				(enabled no)
				(sheetname "")
			)
			(fill
				(thermal_gap 0.5)
				(thermal_bridge_width 0.5)
				(island_removal_mode 0)
			)
			(polygon
				(pts
					(xy 185.1914 -146.0373) (xy 185.6994 -146.0373) (xy 185.6994 -146.4183) (xy 185.1914 -146.4183)
				)
			)
		)
	)
	(footprint ""
		(layer "F.Cu")
		(at 181.60873 -24.431752 90)
		(property "Reference" "Q12W1"
			(at 0 0 90)
			(layer "F.SilkS")
			(hide yes)
			(effects
				(font
					(size 1.27 1.27)
				)
			)
		)
		(property "Value" "*"
			(at -4.572 -7.6835 90)
			(unlocked yes)
			(layer "F.Fab")
			(hide yes)
			(effects
				(font
					(size 1.27 1.016)
					(thickness 0.1524)
				)
			)
		)
		(property "Device Type" "BSL308C-H6327-GP_DISCRET-GB1-BA"
			(at -4.572 -9.2075 90)
			(unlocked yes)
			(layer "F.Fab")
			(hide yes)
			(effects
				(font
					(size 1.27 1.016)
					(thickness 0.1524)
				)
			)
		)
		(duplicate_pad_numbers_are_jumpers no)
		(fp_line
			(start 1.102868 -0.081534)
			(end 1.102868 0.081534)
			(stroke
				(width 0.1524)
				(type default)
			)
			(layer "F.SilkS")
		)
		(fp_line
			(start -1.8796 -0.081534)
			(end 1.102868 -0.081534)
			(stroke
				(width 0.1524)
				(type default)
			)
			(layer "F.SilkS")
		)
		(fp_line
			(start -1.8796 -0.081534)
			(end -1.524 0)
			(stroke
				(width 0.1524)
				(type default)
			)
			(layer "F.SilkS")
		)
		(fp_line
			(start -1.524 0)
			(end -1.8796 0.081534)
			(stroke
				(width 0.1524)
				(type default)
			)
			(layer "F.SilkS")
		)
		(fp_line
			(start 1.102868 0.081534)
			(end -1.8796 0.081534)
			(stroke
				(width 0.1524)
				(type default)
			)
			(layer "F.SilkS")
		)
		(fp_line
			(start -1.8796 0.081534)
			(end -1.8796 -0.081534)
			(stroke
				(width 0.1524)
				(type default)
			)
			(layer "F.SilkS")
		)
		(fp_line
			(start -1.7018 0.3048)
			(end -1.7018 1.8796)
			(stroke
				(width 0.508)
				(type default)
			)
			(layer "F.SilkS")
		)
		(fp_poly
			(pts
				(xy -1.179068 0.081534) (xy -1.179068 -0.081534) (xy 1.102868 -0.081534) (xy 1.102868 0.081534)
			)
			(stroke
				(width 0)
				(type default)
			)
			(fill yes)
			(layer "F.SilkS")
		)
		(fp_rect
			(start -1.4478 1.2446)
			(end 1.4478 -1.2446)
			(stroke
				(width 0)
				(type default)
			)
			(fill no)
			(layer "F.CrtYd")
		)
		(fp_poly
			(pts
				(xy -1.4478 -1.23952) (xy -1.9558 -1.23952) (xy -1.9558 2.1336) (xy 1.9558 2.1336) (xy 1.9558 -2.1336)
				(xy -1.9558 -2.1336) (xy -1.9558 -1.2446) (xy 1.4478 -1.2446) (xy 1.4478 1.2446) (xy -1.4478 1.2446)
			)
			(stroke
				(width 0)
				(type default)
			)
			(fill no)
			(layer "F.CrtYd")
		)
		(fp_rect
			(start -1.9558 2.1336)
			(end 1.9558 -2.1336)
			(stroke
				(width 0)
				(type default)
			)
			(fill no)
			(layer "F.Fab")
		)
		(pad "1" smd rect
			(at -0.950468 0.995934 90)
			(size 0.4572 1.27)
			(layers "F.Cu" "F.Mask" "F.Paste")
			(net "PWRGD_PVDDQ_ABC")
		)
		(pad "2" smd rect
			(at 0 0.995934 90)
			(size 0.4572 1.27)
			(layers "F.Cu" "F.Mask" "F.Paste")
			(net "P12V_NVDIMM_ABC")
		)
		(pad "3" smd rect
			(at 0.950468 0.995934 90)
			(size 0.4572 1.27)
			(layers "F.Cu" "F.Mask" "F.Paste")
			(net "PWRGD_PVDDQ_ABC_N")
		)
		(pad "4" smd rect
			(at 0.950468 -0.995934 90)
			(size 0.4572 1.27)
			(layers "F.Cu" "F.Mask" "F.Paste")
			(net "P12V_NVDIMM_ABC_D")
		)
		(pad "5" smd rect
			(at 0 -0.995934 90)
			(size 0.4572 1.27)
			(layers "F.Cu" "F.Mask" "F.Paste")
			(net "GND")
		)
		(pad "6" smd rect
			(at -0.950468 -0.995934 90)
			(size 0.4572 1.27)
			(layers "F.Cu" "F.Mask" "F.Paste")
			(net "PWRGD_PVDDQ_ABC_N")
		)
	)
	(footprint ""
		(layer "F.Cu")
		(at 9.017 13.2715 -90)
		(property "Reference" "T1P31"
			(at 0 0 270)
			(layer "F.SilkS")
			(hide yes)
			(effects
				(font
					(size 1.27 1.27)
				)
			)
		)
		(property "Value" "*"
			(at 0 -3.44805 270)
			(unlocked yes)
			(layer "F.Fab")
			(hide yes)
			(effects
				(font
					(size 0.889 0.889)
					(thickness 0.1524)
				)
			)
		)
		(property "Device Type" "TPAD-SE-2P-GP_DISCRET-GA1-TPADA"
			(at 0 -4.97205 270)
			(unlocked yes)
			(layer "F.Fab")
			(hide yes)
			(effects
				(font
					(size 0.889 0.889)
					(thickness 0.1524)
				)
			)
		)
		(duplicate_pad_numbers_are_jumpers no)
		(fp_line
			(start -1.016 2.286)
			(end -1.016 -2.286)
			(stroke
				(width 0.1524)
				(type default)
			)
			(layer "F.SilkS")
		)
		(fp_line
			(start 1.016 2.286)
			(end -1.016 2.286)
			(stroke
				(width 0.1524)
				(type default)
			)
			(layer "F.SilkS")
		)
		(fp_line
			(start -1.016 -2.286)
			(end 1.016 -2.286)
			(stroke
				(width 0.1524)
				(type default)
			)
			(layer "F.SilkS")
		)
		(fp_line
			(start 1.016 -2.286)
			(end 1.016 2.286)
			(stroke
				(width 0.1524)
				(type default)
			)
			(layer "F.SilkS")
		)
		(fp_rect
			(start -1.27 2.54)
			(end 1.27 -2.54)
			(stroke
				(width 0)
				(type default)
			)
			(fill no)
			(layer "F.CrtYd")
		)
		(fp_rect
			(start -1.27 2.54)
			(end 1.27 -2.54)
			(stroke
				(width 0)
				(type default)
			)
			(fill no)
			(layer "F.Fab")
		)
		(pad "1" thru_hole circle
			(at 0 -1.27 270)
			(size 1.524 1.524)
			(drill 0.9144)
			(layers "*.Cu" "*.Mask")
			(remove_unused_layers no)
			(net "L1_50OHM_6INCH")
			(clearance -0.0508)
			(thermal_gap 0.127)
			(padstack
				(mode front_inner_back)
				(layer "Inner"
					(shape circle)
					(size 1.1684 1.1684)
					(clearance 0.127)
				)
				(layer "B.Cu"
					(shape circle)
					(size 1.524 1.524)
					(clearance -0.0508)
				)
			)
		)
		(pad "GND1" thru_hole rect
			(at 0 1.27 270)
			(size 1.524 1.524)
			(drill 0.9144)
			(layers "*.Cu" "*.Mask")
			(remove_unused_layers no)
			(net "GND")
			(clearance -0.0508)
			(thermal_gap 0.127)
			(padstack
				(mode front_inner_back)
				(layer "Inner"
					(shape circle)
					(size 1.1684 1.1684)
					(clearance 0.127)
				)
				(layer "B.Cu"
					(shape rect)
					(size 1.524 1.524)
					(clearance -0.0508)
				)
			)
		)
	)
)
